(kicad_pcb
	(version 20260206)
	(generator "pcbnew")
	(generator_version "10.0")
	(general
		(thickness 1.6)
		(legacy_teardrops no)
	)
	(paper "A4")
	(title_block
		(title "01162023_DA0F0TEBIF0_F0T_Expander_BD_F_brd_V02_OCP.brd")
		(comment 1 "Grand Teton / footprints 7606-7613 of 9728")
	)
	(layers
		(0 "F.Cu" signal "TOP")
		(4 "In1.Cu" signal "GND")
		(6 "In2.Cu" signal "VCC")
		(8 "In3.Cu" signal "VCC1")
		(10 "In4.Cu" signal "GND1")
		(12 "In5.Cu" signal "IN1")
		(14 "In6.Cu" signal "GND2")
		(16 "In7.Cu" signal "IN2")
		(18 "In8.Cu" signal "GND3")
		(20 "In9.Cu" signal "IN3")
		(22 "In10.Cu" signal "GND4")
		(24 "In11.Cu" signal "IN4")
		(26 "In12.Cu" signal "GND5")
		(28 "In13.Cu" signal "IN5")
		(30 "In14.Cu" signal "GND6")
		(32 "In15.Cu" signal "IN6")
		(34 "In16.Cu" signal "GND7")
		(2 "B.Cu" signal "BOTTOM")
		(9 "F.Adhes" user "F.Adhesive")
		(11 "B.Adhes" user "B.Adhesive")
		(13 "F.Paste" user "Package Geometry/Pastemask Top")
		(15 "B.Paste" user "Package Geometry/Pastemask Bottom")
		(5 "F.SilkS" user "Ref Des/Silkscreen Top")
		(7 "B.SilkS" user "Ref Des/Silkscreen Bottom")
		(1 "F.Mask" user "Board Geometry/Soldermask Top")
		(3 "B.Mask" user "Board Geometry/Soldermask Bottom")
		(17 "Dwgs.User" user "User.Drawings")
		(19 "Cmts.User" user "User.Comments")
		(21 "Eco1.User" user "User.Eco1")
		(23 "Eco2.User" user "User.Eco2")
		(25 "Edge.Cuts" user "Board Geometry/Outline")
		(27 "Margin" user)
		(31 "F.CrtYd" user "Package Geometry/Place Bound Top")
		(29 "B.CrtYd" user "Package Geometry/Place Bound Bottom")
		(35 "F.Fab" user "Ref Des/Assembly Top")
		(33 "B.Fab" user "Ref Des/Assembly Bottom")
	)
	(footprint ""
		(layer "B.Cu")
		(at 107.621832 -348.226888 180)
		(property "Reference" "R6372"
			(at 0 0 0)
			(layer "B.SilkS")
			(hide yes)
			(effects
				(font
					(size 1.27 1.27)
				)
				(justify mirror)
			)
		)
		(property "Value" ""
			(at 0 0 0)
			(layer "B.Fab")
			(effects
				(font
					(size 1.27 1.27)
				)
				(justify mirror)
			)
		)
		(duplicate_pad_numbers_are_jumpers no)
		(fp_line
			(start 0.7874 0.4064)
			(end 0.7874 -0.4064)
			(stroke
				(width 0.1524)
				(type default)
			)
			(layer "B.SilkS")
		)
		(fp_line
			(start 0.7874 -0.4064)
			(end -0.7874 -0.4064)
			(stroke
				(width 0.1524)
				(type default)
			)
			(layer "B.SilkS")
		)
		(fp_line
			(start -0.7874 0.4064)
			(end 0.7874 0.4064)
			(stroke
				(width 0.1524)
				(type default)
			)
			(layer "B.SilkS")
		)
		(fp_line
			(start -0.7874 -0.4064)
			(end -0.7874 0.4064)
			(stroke
				(width 0.1524)
				(type default)
			)
			(layer "B.SilkS")
		)
		(fp_line
			(start 0.67945 0.3048)
			(end 0.67945 -0.305054)
			(stroke
				(width 0.1)
				(type default)
			)
			(layer "B.Fab")
		)
		(fp_line
			(start 0.67945 -0.305054)
			(end 0.12065 -0.305054)
			(stroke
				(width 0.1)
				(type default)
			)
			(layer "B.Fab")
		)
		(fp_line
			(start 0.12065 0.3048)
			(end 0.67945 0.3048)
			(stroke
				(width 0.1)
				(type default)
			)
			(layer "B.Fab")
		)
		(fp_line
			(start 0.12065 0.2794)
			(end 0.12065 0.3048)
			(stroke
				(width 0.1)
				(type default)
			)
			(layer "B.Fab")
		)
		(fp_line
			(start 0.12065 -0.2794)
			(end -0.12065 -0.2794)
			(stroke
				(width 0.1)
				(type default)
			)
			(layer "B.Fab")
		)
		(fp_line
			(start 0.12065 -0.305054)
			(end 0.12065 -0.2794)
			(stroke
				(width 0.1)
				(type default)
			)
			(layer "B.Fab")
		)
		(fp_line
			(start -0.120396 0.3048)
			(end -0.120396 0.2794)
			(stroke
				(width 0.1)
				(type default)
			)
			(layer "B.Fab")
		)
		(fp_line
			(start -0.120396 0.2794)
			(end 0.12065 0.2794)
			(stroke
				(width 0.1)
				(type default)
			)
			(layer "B.Fab")
		)
		(fp_line
			(start -0.12065 -0.2794)
			(end -0.12065 -0.3048)
			(stroke
				(width 0.1)
				(type default)
			)
			(layer "B.Fab")
		)
		(fp_line
			(start -0.12065 -0.3048)
			(end -0.67945 -0.3048)
			(stroke
				(width 0.1)
				(type default)
			)
			(layer "B.Fab")
		)
		(fp_line
			(start -0.67945 0.3048)
			(end -0.120396 0.3048)
			(stroke
				(width 0.1)
				(type default)
			)
			(layer "B.Fab")
		)
		(fp_line
			(start -0.67945 -0.3048)
			(end -0.67945 0.3048)
			(stroke
				(width 0.1)
				(type default)
			)
			(layer "B.Fab")
		)
		(pad "1" smd circle
			(at 0.40005 0)
			(size 0 0)
			(layers "B.Cu" "B.Mask" "B.Paste")
			(net "PU_9ZXL0451E_S3_HBW")
		)
		(pad "2" smd circle
			(at -0.40005 0)
			(size 0 0)
			(layers "B.Cu" "B.Mask" "B.Paste")
			(net "GND")
		)
	)
	(footprint ""
		(layer "B.Cu")
		(at 185.250074 -294.4749 180)
		(property "Reference" "C1417"
			(at 0 0 0)
			(layer "B.SilkS")
			(hide yes)
			(effects
				(font
					(size 1.27 1.27)
				)
				(justify mirror)
			)
		)
		(property "Value" ""
			(at 0 0 0)
			(layer "B.Fab")
			(effects
				(font
					(size 1.27 1.27)
				)
				(justify mirror)
			)
		)
		(duplicate_pad_numbers_are_jumpers no)
		(fp_line
			(start 0.299974 0.150114)
			(end 0.299974 -0.150114)
			(stroke
				(width 0.1)
				(type default)
			)
			(layer "B.Fab")
		)
		(fp_line
			(start 0.299974 -0.150114)
			(end -0.299974 -0.150114)
			(stroke
				(width 0.1)
				(type default)
			)
			(layer "B.Fab")
		)
		(fp_line
			(start -0.299974 0.150114)
			(end 0.299974 0.150114)
			(stroke
				(width 0.1)
				(type default)
			)
			(layer "B.Fab")
		)
		(fp_line
			(start -0.299974 -0.150114)
			(end -0.299974 0.150114)
			(stroke
				(width 0.1)
				(type default)
			)
			(layer "B.Fab")
		)
		(pad "1" smd rect
			(at 0.2667 0)
			(size 0.3048 0.381)
			(layers "B.Cu" "B.Mask" "B.Paste")
			(net "P0V8_SERDES_VDDA_PEX1")
		)
		(pad "2" smd rect
			(at -0.2667 0)
			(size 0.3048 0.381)
			(layers "B.Cu" "B.Mask" "B.Paste")
			(net "GND")
		)
	)
	(footprint ""
		(layer "B.Cu")
		(at 181.44998 -301.599854 -90)
		(property "Reference" "C1451"
			(at 0 0 90)
			(layer "B.SilkS")
			(hide yes)
			(effects
				(font
					(size 1.27 1.27)
				)
				(justify mirror)
			)
		)
		(property "Value" ""
			(at 0 0 90)
			(layer "B.Fab")
			(effects
				(font
					(size 1.27 1.27)
				)
				(justify mirror)
			)
		)
		(duplicate_pad_numbers_are_jumpers no)
		(fp_line
			(start -0.299974 0.150114)
			(end 0.299974 0.150114)
			(stroke
				(width 0.1)
				(type default)
			)
			(layer "B.Fab")
		)
		(fp_line
			(start 0.299974 0.150114)
			(end 0.299974 -0.150114)
			(stroke
				(width 0.1)
				(type default)
			)
			(layer "B.Fab")
		)
		(fp_line
			(start -0.299974 -0.150114)
			(end -0.299974 0.150114)
			(stroke
				(width 0.1)
				(type default)
			)
			(layer "B.Fab")
		)
		(fp_line
			(start 0.299974 -0.150114)
			(end -0.299974 -0.150114)
			(stroke
				(width 0.1)
				(type default)
			)
			(layer "B.Fab")
		)
		(pad "1" smd rect
			(at 0.2667 0 90)
			(size 0.3048 0.381)
			(layers "B.Cu" "B.Mask" "B.Paste")
			(net "P0V8_SERDES_VDDA_PEX1")
		)
		(pad "2" smd rect
			(at -0.2667 0 90)
			(size 0.3048 0.381)
			(layers "B.Cu" "B.Mask" "B.Paste")
			(net "GND")
		)
	)
	(footprint ""
		(layer "B.Cu")
		(at 261.904226 -224.75063 180)
		(property "Reference" "R6170"
			(at 0 0 0)
			(layer "B.SilkS")
			(hide yes)
			(effects
				(font
					(size 1.27 1.27)
				)
				(justify mirror)
			)
		)
		(property "Value" ""
			(at 0 0 0)
			(layer "B.Fab")
			(effects
				(font
					(size 1.27 1.27)
				)
				(justify mirror)
			)
		)
		(duplicate_pad_numbers_are_jumpers no)
		(fp_line
			(start 0.7874 0.4064)
			(end 0.7874 -0.4064)
			(stroke
				(width 0.1524)
				(type default)
			)
			(layer "B.SilkS")
		)
		(fp_line
			(start 0.7874 -0.4064)
			(end -0.7874 -0.4064)
			(stroke
				(width 0.1524)
				(type default)
			)
			(layer "B.SilkS")
		)
		(fp_line
			(start -0.7874 0.4064)
			(end 0.7874 0.4064)
			(stroke
				(width 0.1524)
				(type default)
			)
			(layer "B.SilkS")
		)
		(fp_line
			(start -0.7874 -0.4064)
			(end -0.7874 0.4064)
			(stroke
				(width 0.1524)
				(type default)
			)
			(layer "B.SilkS")
		)
		(fp_line
			(start 0.67945 0.3048)
			(end 0.67945 -0.305054)
			(stroke
				(width 0.1)
				(type default)
			)
			(layer "B.Fab")
		)
		(fp_line
			(start 0.67945 -0.305054)
			(end 0.12065 -0.305054)
			(stroke
				(width 0.1)
				(type default)
			)
			(layer "B.Fab")
		)
		(fp_line
			(start 0.12065 0.3048)
			(end 0.67945 0.3048)
			(stroke
				(width 0.1)
				(type default)
			)
			(layer "B.Fab")
		)
		(fp_line
			(start 0.12065 0.2794)
			(end 0.12065 0.3048)
			(stroke
				(width 0.1)
				(type default)
			)
			(layer "B.Fab")
		)
		(fp_line
			(start 0.12065 -0.2794)
			(end -0.12065 -0.2794)
			(stroke
				(width 0.1)
				(type default)
			)
			(layer "B.Fab")
		)
		(fp_line
			(start 0.12065 -0.305054)
			(end 0.12065 -0.2794)
			(stroke
				(width 0.1)
				(type default)
			)
			(layer "B.Fab")
		)
		(fp_line
			(start -0.120396 0.3048)
			(end -0.120396 0.2794)
			(stroke
				(width 0.1)
				(type default)
			)
			(layer "B.Fab")
		)
		(fp_line
			(start -0.120396 0.2794)
			(end 0.12065 0.2794)
			(stroke
				(width 0.1)
				(type default)
			)
			(layer "B.Fab")
		)
		(fp_line
			(start -0.12065 -0.2794)
			(end -0.12065 -0.3048)
			(stroke
				(width 0.1)
				(type default)
			)
			(layer "B.Fab")
		)
		(fp_line
			(start -0.12065 -0.3048)
			(end -0.67945 -0.3048)
			(stroke
				(width 0.1)
				(type default)
			)
			(layer "B.Fab")
		)
		(fp_line
			(start -0.67945 0.3048)
			(end -0.120396 0.3048)
			(stroke
				(width 0.1)
				(type default)
			)
			(layer "B.Fab")
		)
		(fp_line
			(start -0.67945 -0.3048)
			(end -0.67945 0.3048)
			(stroke
				(width 0.1)
				(type default)
			)
			(layer "B.Fab")
		)
		(pad "1" smd circle
			(at 0.40005 0)
			(size 0 0)
			(layers "B.Cu" "B.Mask" "B.Paste")
			(net "SPI_PEX2_RST_R_N")
		)
		(pad "2" smd circle
			(at -0.40005 0)
			(size 0 0)
			(layers "B.Cu" "B.Mask" "B.Paste")
			(net "GND")
		)
	)
	(footprint ""
		(layer "B.Cu")
		(at 140.894816 -204.949806)
		(property "Reference" "L6"
			(at 0 0 0)
			(layer "B.SilkS")
			(hide yes)
			(effects
				(font
					(size 1.27 1.27)
				)
				(justify mirror)
			)
		)
		(property "Value" ""
			(at 0 0 0)
			(layer "B.Fab")
			(effects
				(font
					(size 1.27 1.27)
				)
				(justify mirror)
			)
		)
		(duplicate_pad_numbers_are_jumpers no)
		(fp_line
			(start -1.27 0.5842)
			(end -1.27 -0.5842)
			(stroke
				(width 0.1524)
				(type default)
			)
			(layer "B.SilkS")
		)
		(fp_line
			(start -1.27 0.5842)
			(end 1.27 0.5842)
			(stroke
				(width 0.1524)
				(type default)
			)
			(layer "B.SilkS")
		)
		(fp_line
			(start 1.27 -0.5842)
			(end -1.27 -0.5842)
			(stroke
				(width 0.1524)
				(type default)
			)
			(layer "B.SilkS")
		)
		(fp_line
			(start 1.27 -0.5588)
			(end 1.27 -0.5842)
			(stroke
				(width 0.1524)
				(type default)
			)
			(layer "B.SilkS")
		)
		(fp_line
			(start 1.27 0.5842)
			(end 1.27 -0.5842)
			(stroke
				(width 0.1524)
				(type default)
			)
			(layer "B.SilkS")
		)
		(fp_line
			(start -1.1938 -0.406654)
			(end -1.1938 0.4064)
			(stroke
				(width 0.1)
				(type default)
			)
			(layer "B.Fab")
		)
		(fp_line
			(start -1.1938 0.4064)
			(end -0.9144 0.4064)
			(stroke
				(width 0.1)
				(type default)
			)
			(layer "B.Fab")
		)
		(fp_line
			(start -0.9144 -0.508)
			(end -0.9144 -0.406654)
			(stroke
				(width 0.1)
				(type default)
			)
			(layer "B.Fab")
		)
		(fp_line
			(start -0.9144 -0.406654)
			(end -1.1938 -0.406654)
			(stroke
				(width 0.1)
				(type default)
			)
			(layer "B.Fab")
		)
		(fp_line
			(start -0.9144 0.4064)
			(end -0.9144 0.508)
			(stroke
				(width 0.1)
				(type default)
			)
			(layer "B.Fab")
		)
		(fp_line
			(start -0.9144 0.508)
			(end 0.9144 0.508)
			(stroke
				(width 0.1)
				(type default)
			)
			(layer "B.Fab")
		)
		(fp_line
			(start 0.9144 -0.508)
			(end -0.9144 -0.508)
			(stroke
				(width 0.1)
				(type default)
			)
			(layer "B.Fab")
		)
		(fp_line
			(start 0.9144 -0.406654)
			(end 0.9144 -0.508)
			(stroke
				(width 0.1)
				(type default)
			)
			(layer "B.Fab")
		)
		(fp_line
			(start 0.9144 0.406654)
			(end 1.194308 0.406654)
			(stroke
				(width 0.1)
				(type default)
			)
			(layer "B.Fab")
		)
		(fp_line
			(start 0.9144 0.508)
			(end 0.9144 0.406654)
			(stroke
				(width 0.1)
				(type default)
			)
			(layer "B.Fab")
		)
		(fp_line
			(start 1.194308 -0.406654)
			(end 0.9144 -0.406654)
			(stroke
				(width 0.1)
				(type default)
			)
			(layer "B.Fab")
		)
		(fp_line
			(start 1.194308 0.406654)
			(end 1.194308 -0.406654)
			(stroke
				(width 0.1)
				(type default)
			)
			(layer "B.Fab")
		)
		(pad "1" smd rect
			(at 0.7366 0 270)
			(size 0.7112 0.8128)
			(layers "B.Cu" "B.Mask" "B.Paste")
			(net "P3V3_AUX")
		)
		(pad "2" smd rect
			(at -0.7366 0 270)
			(size 0.7112 0.8128)
			(layers "B.Cu" "B.Mask" "B.Paste")
			(net "P3V3_CLI_VPLL")
		)
	)
	(footprint ""
		(layer "B.Cu")
		(at 366.268 -237.744)
		(property "Reference" "R914"
			(at 0 0 0)
			(layer "B.SilkS")
			(hide yes)
			(effects
				(font
					(size 1.27 1.27)
				)
				(justify mirror)
			)
		)
		(property "Value" ""
			(at 0 0 0)
			(layer "B.Fab")
			(effects
				(font
					(size 1.27 1.27)
				)
				(justify mirror)
			)
		)
		(duplicate_pad_numbers_are_jumpers no)
		(fp_line
			(start -0.7874 -0.4064)
			(end -0.7874 0.4064)
			(stroke
				(width 0.1524)
				(type default)
			)
			(layer "B.SilkS")
		)
		(fp_line
			(start -0.7874 0.4064)
			(end 0.7874 0.4064)
			(stroke
				(width 0.1524)
				(type default)
			)
			(layer "B.SilkS")
		)
		(fp_line
			(start 0.7874 -0.4064)
			(end -0.7874 -0.4064)
			(stroke
				(width 0.1524)
				(type default)
			)
			(layer "B.SilkS")
		)
		(fp_line
			(start 0.7874 0.4064)
			(end 0.7874 -0.4064)
			(stroke
				(width 0.1524)
				(type default)
			)
			(layer "B.SilkS")
		)
		(fp_line
			(start -0.67945 -0.3048)
			(end -0.67945 0.3048)
			(stroke
				(width 0.1)
				(type default)
			)
			(layer "B.Fab")
		)
		(fp_line
			(start -0.67945 0.3048)
			(end -0.120396 0.3048)
			(stroke
				(width 0.1)
				(type default)
			)
			(layer "B.Fab")
		)
		(fp_line
			(start -0.12065 -0.3048)
			(end -0.67945 -0.3048)
			(stroke
				(width 0.1)
				(type default)
			)
			(layer "B.Fab")
		)
		(fp_line
			(start -0.12065 -0.2794)
			(end -0.12065 -0.3048)
			(stroke
				(width 0.1)
				(type default)
			)
			(layer "B.Fab")
		)
		(fp_line
			(start -0.120396 0.2794)
			(end 0.12065 0.2794)
			(stroke
				(width 0.1)
				(type default)
			)
			(layer "B.Fab")
		)
		(fp_line
			(start -0.120396 0.3048)
			(end -0.120396 0.2794)
			(stroke
				(width 0.1)
				(type default)
			)
			(layer "B.Fab")
		)
		(fp_line
			(start 0.12065 -0.305054)
			(end 0.12065 -0.2794)
			(stroke
				(width 0.1)
				(type default)
			)
			(layer "B.Fab")
		)
		(fp_line
			(start 0.12065 -0.2794)
			(end -0.12065 -0.2794)
			(stroke
				(width 0.1)
				(type default)
			)
			(layer "B.Fab")
		)
		(fp_line
			(start 0.12065 0.2794)
			(end 0.12065 0.3048)
			(stroke
				(width 0.1)
				(type default)
			)
			(layer "B.Fab")
		)
		(fp_line
			(start 0.12065 0.3048)
			(end 0.67945 0.3048)
			(stroke
				(width 0.1)
				(type default)
			)
			(layer "B.Fab")
		)
		(fp_line
			(start 0.67945 -0.305054)
			(end 0.12065 -0.305054)
			(stroke
				(width 0.1)
				(type default)
			)
			(layer "B.Fab")
		)
		(fp_line
			(start 0.67945 0.3048)
			(end 0.67945 -0.305054)
			(stroke
				(width 0.1)
				(type default)
			)
			(layer "B.Fab")
		)
		(pad "1" smd circle
			(at 0.40005 0 180)
			(size 0 0)
			(layers "B.Cu" "B.Mask" "B.Paste")
			(net "FT4232_SDB_EEPROM_R_SDA")
		)
		(pad "2" smd circle
			(at -0.40005 0 180)
			(size 0 0)
			(layers "B.Cu" "B.Mask" "B.Paste")
			(net "FT4232_SDB_EEPROM_SDA")
		)
	)
	(footprint ""
		(layer "B.Cu")
		(at 404.149814 -288.299906 90)
		(property "Reference" "C3454"
			(at 0 0 90)
			(layer "B.SilkS")
			(hide yes)
			(effects
				(font
					(size 1.27 1.27)
				)
				(justify mirror)
			)
		)
		(property "Value" ""
			(at 0 0 90)
			(layer "B.Fab")
			(effects
				(font
					(size 1.27 1.27)
				)
				(justify mirror)
			)
		)
		(duplicate_pad_numbers_are_jumpers no)
		(fp_line
			(start 0.299974 -0.150114)
			(end -0.299974 -0.150114)
			(stroke
				(width 0.1)
				(type default)
			)
			(layer "B.Fab")
		)
		(fp_line
			(start -0.299974 -0.150114)
			(end -0.299974 0.150114)
			(stroke
				(width 0.1)
				(type default)
			)
			(layer "B.Fab")
		)
		(fp_line
			(start 0.299974 0.150114)
			(end 0.299974 -0.150114)
			(stroke
				(width 0.1)
				(type default)
			)
			(layer "B.Fab")
		)
		(fp_line
			(start -0.299974 0.150114)
			(end 0.299974 0.150114)
			(stroke
				(width 0.1)
				(type default)
			)
			(layer "B.Fab")
		)
		(pad "1" smd rect
			(at 0.2667 0 270)
			(size 0.3048 0.381)
			(layers "B.Cu" "B.Mask" "B.Paste")
			(net "P1V25_PEX3")
		)
		(pad "2" smd rect
			(at -0.2667 0 270)
			(size 0.3048 0.381)
			(layers "B.Cu" "B.Mask" "B.Paste")
			(net "GND")
		)
	)
	(footprint ""
		(layer "B.Cu")
		(at 55.849774 -288.299906 90)
		(property "Reference" "C2933"
			(at 0 0 90)
			(layer "B.SilkS")
			(hide yes)
			(effects
				(font
					(size 1.27 1.27)
				)
				(justify mirror)
			)
		)
		(property "Value" ""
			(at 0 0 90)
			(layer "B.Fab")
			(effects
				(font
					(size 1.27 1.27)
				)
				(justify mirror)
			)
		)
		(duplicate_pad_numbers_are_jumpers no)
		(fp_line
			(start 0.299974 -0.150114)
			(end -0.299974 -0.150114)
			(stroke
				(width 0.1)
				(type default)
			)
			(layer "B.Fab")
		)
		(fp_line
			(start -0.299974 -0.150114)
			(end -0.299974 0.150114)
			(stroke
				(width 0.1)
				(type default)
			)
			(layer "B.Fab")
		)
		(fp_line
			(start 0.299974 0.150114)
			(end 0.299974 -0.150114)
			(stroke
				(width 0.1)
				(type default)
			)
			(layer "B.Fab")
		)
		(fp_line
			(start -0.299974 0.150114)
			(end 0.299974 0.150114)
			(stroke
				(width 0.1)
				(type default)
			)
			(layer "B.Fab")
		)
		(pad "1" smd rect
			(at 0.2667 0 270)
			(size 0.3048 0.381)
			(layers "B.Cu" "B.Mask" "B.Paste")
			(net "P1V25_PEX0")
		)
		(pad "2" smd rect
			(at -0.2667 0 270)
			(size 0.3048 0.381)
			(layers "B.Cu" "B.Mask" "B.Paste")
			(net "GND")
		)
	)
)
